(kicad_pcb
	(version 20260206)
	(generator "pcbnew")
	(generator_version "10.0")
	(general
		(thickness 1.6)
		(legacy_teardrops no)
	)
	(paper "A4")
	(title_block
		(title "04192023_DAF0TMB3IC0_F0TG_MB_C_brd_V02_OCP.brd")
		(comment 1 "Grand Teton / footprints 3728-3734 of 8354")
	)
	(layers
		(0 "F.Cu" signal "TOP")
		(4 "In1.Cu" signal "GND")
		(6 "In2.Cu" signal "IN1")
		(8 "In3.Cu" signal "GND1")
		(10 "In4.Cu" signal "IN2")
		(12 "In5.Cu" signal "GND2")
		(14 "In6.Cu" signal "IN3")
		(16 "In7.Cu" signal "GND3")
		(18 "In8.Cu" signal "VCC")
		(20 "In9.Cu" signal "VCC1")
		(22 "In10.Cu" signal "GND4")
		(24 "In11.Cu" signal "IN4")
		(26 "In12.Cu" signal "GND5")
		(28 "In13.Cu" signal "IN5")
		(30 "In14.Cu" signal "GND6")
		(32 "In15.Cu" signal "IN6")
		(34 "In16.Cu" signal "GND7")
		(2 "B.Cu" signal "BOTTOM")
		(9 "F.Adhes" user "F.Adhesive")
		(11 "B.Adhes" user "B.Adhesive")
		(13 "F.Paste" user "Package Geometry/Pastemask Top")
		(15 "B.Paste" user "Package Geometry/Pastemask Bottom")
		(5 "F.SilkS" user "Ref Des/Silkscreen Top")
		(7 "B.SilkS" user "Ref Des/Silkscreen Bottom")
		(1 "F.Mask" user "Board Geometry/Soldermask Top")
		(3 "B.Mask" user "Board Geometry/Soldermask Bottom")
		(17 "Dwgs.User" user "User.Drawings")
		(19 "Cmts.User" user "User.Comments")
		(21 "Eco1.User" user "User.Eco1")
		(23 "Eco2.User" user "User.Eco2")
		(25 "Edge.Cuts" user "Board Geometry/Outline")
		(27 "Margin" user)
		(31 "F.CrtYd" user "Package Geometry/Place Bound Top")
		(29 "B.CrtYd" user "Package Geometry/Place Bound Bottom")
		(35 "F.Fab" user "Ref Des/Assembly Top")
		(33 "B.Fab" user "Ref Des/Assembly Bottom")
	)
	(footprint ""
		(layer "F.Cu")
		(at 217.861134 -97.54362)
		(property "Reference" "R9029"
			(at 0 0 0)
			(layer "F.SilkS")
			(hide yes)
			(effects
				(font
					(size 1.27 1.27)
				)
			)
		)
		(property "Value" ""
			(at 0 0 0)
			(layer "F.Fab")
			(effects
				(font
					(size 1.27 1.27)
				)
			)
		)
		(duplicate_pad_numbers_are_jumpers no)
		(fp_line
			(start -0.7874 -0.4064)
			(end 0.7874 -0.4064)
			(stroke
				(width 0.1524)
				(type default)
			)
			(layer "F.SilkS")
		)
		(fp_line
			(start -0.7874 0.4064)
			(end -0.7874 -0.4064)
			(stroke
				(width 0.1524)
				(type default)
			)
			(layer "F.SilkS")
		)
		(fp_line
			(start 0.7874 -0.4064)
			(end 0.7874 0.4064)
			(stroke
				(width 0.1524)
				(type default)
			)
			(layer "F.SilkS")
		)
		(fp_line
			(start 0.7874 0.4064)
			(end -0.7874 0.4064)
			(stroke
				(width 0.1524)
				(type default)
			)
			(layer "F.SilkS")
		)
		(fp_line
			(start -0.67945 -0.305054)
			(end -0.12065 -0.305054)
			(stroke
				(width 0.1)
				(type default)
			)
			(layer "F.Fab")
		)
		(fp_line
			(start -0.67945 0.3048)
			(end -0.67945 -0.305054)
			(stroke
				(width 0.1)
				(type default)
			)
			(layer "F.Fab")
		)
		(fp_line
			(start -0.12065 -0.305054)
			(end -0.12065 -0.2794)
			(stroke
				(width 0.1)
				(type default)
			)
			(layer "F.Fab")
		)
		(fp_line
			(start -0.12065 -0.2794)
			(end 0.12065 -0.2794)
			(stroke
				(width 0.1)
				(type default)
			)
			(layer "F.Fab")
		)
		(fp_line
			(start -0.12065 0.2794)
			(end -0.12065 0.3048)
			(stroke
				(width 0.1)
				(type default)
			)
			(layer "F.Fab")
		)
		(fp_line
			(start -0.12065 0.3048)
			(end -0.67945 0.3048)
			(stroke
				(width 0.1)
				(type default)
			)
			(layer "F.Fab")
		)
		(fp_line
			(start 0.120396 0.2794)
			(end -0.12065 0.2794)
			(stroke
				(width 0.1)
				(type default)
			)
			(layer "F.Fab")
		)
		(fp_line
			(start 0.120396 0.3048)
			(end 0.120396 0.2794)
			(stroke
				(width 0.1)
				(type default)
			)
			(layer "F.Fab")
		)
		(fp_line
			(start 0.12065 -0.3048)
			(end 0.67945 -0.3048)
			(stroke
				(width 0.1)
				(type default)
			)
			(layer "F.Fab")
		)
		(fp_line
			(start 0.12065 -0.2794)
			(end 0.12065 -0.3048)
			(stroke
				(width 0.1)
				(type default)
			)
			(layer "F.Fab")
		)
		(fp_line
			(start 0.67945 -0.3048)
			(end 0.67945 0.3048)
			(stroke
				(width 0.1)
				(type default)
			)
			(layer "F.Fab")
		)
		(fp_line
			(start 0.67945 0.3048)
			(end 0.120396 0.3048)
			(stroke
				(width 0.1)
				(type default)
			)
			(layer "F.Fab")
		)
		(pad "1" smd circle
			(at -0.40005 0)
			(size 0 0)
			(layers "F.Cu" "F.Mask" "F.Paste")
			(net "OCP_SFF_AUX_PWR_EN_R3")
		)
		(pad "2" smd circle
			(at 0.40005 0)
			(size 0 0)
			(layers "F.Cu" "F.Mask" "F.Paste")
			(net "HP_LVC3_OCP_V3_1_PWRGD_R1")
		)
	)
	(footprint ""
		(layer "F.Cu")
		(at 285.24454 -401.395692 180)
		(property "Reference" "C1786"
			(at 0 0 180)
			(layer "F.SilkS")
			(hide yes)
			(effects
				(font
					(size 1.27 1.27)
				)
			)
		)
		(property "Value" ""
			(at 0 0 180)
			(layer "F.Fab")
			(effects
				(font
					(size 1.27 1.27)
				)
			)
		)
		(duplicate_pad_numbers_are_jumpers no)
		(fp_line
			(start 1.2954 0.5842)
			(end -1.2954 0.5842)
			(stroke
				(width 0.1524)
				(type default)
			)
			(layer "F.SilkS")
		)
		(fp_line
			(start 1.2954 -0.5842)
			(end 1.2954 0.5842)
			(stroke
				(width 0.1524)
				(type default)
			)
			(layer "F.SilkS")
		)
		(fp_line
			(start -1.2954 0.5842)
			(end -1.2954 -0.5842)
			(stroke
				(width 0.1524)
				(type default)
			)
			(layer "F.SilkS")
		)
		(fp_line
			(start -1.2954 -0.5842)
			(end 1.2954 -0.5842)
			(stroke
				(width 0.1524)
				(type default)
			)
			(layer "F.SilkS")
		)
		(fp_line
			(start 1.1938 0.4064)
			(end 0.8636 0.4064)
			(stroke
				(width 0.1)
				(type default)
			)
			(layer "F.Fab")
		)
		(fp_line
			(start 1.1938 -0.4064)
			(end 1.1938 0.4064)
			(stroke
				(width 0.1)
				(type default)
			)
			(layer "F.Fab")
		)
		(fp_line
			(start 0.8636 0.4572)
			(end -0.8636 0.4572)
			(stroke
				(width 0.1)
				(type default)
			)
			(layer "F.Fab")
		)
		(fp_line
			(start 0.8636 0.4064)
			(end 0.8636 0.4572)
			(stroke
				(width 0.1)
				(type default)
			)
			(layer "F.Fab")
		)
		(fp_line
			(start 0.8636 -0.4064)
			(end 1.1938 -0.4064)
			(stroke
				(width 0.1)
				(type default)
			)
			(layer "F.Fab")
		)
		(fp_line
			(start 0.8636 -0.4572)
			(end 0.8636 -0.4064)
			(stroke
				(width 0.1)
				(type default)
			)
			(layer "F.Fab")
		)
		(fp_line
			(start -0.8636 0.4572)
			(end -0.8636 0.4064)
			(stroke
				(width 0.1)
				(type default)
			)
			(layer "F.Fab")
		)
		(fp_line
			(start -0.8636 0.4064)
			(end -1.1938 0.4064)
			(stroke
				(width 0.1)
				(type default)
			)
			(layer "F.Fab")
		)
		(fp_line
			(start -0.8636 -0.4064)
			(end -0.8636 -0.4572)
			(stroke
				(width 0.1)
				(type default)
			)
			(layer "F.Fab")
		)
		(fp_line
			(start -0.8636 -0.4572)
			(end 0.8636 -0.4572)
			(stroke
				(width 0.1)
				(type default)
			)
			(layer "F.Fab")
		)
		(fp_line
			(start -1.1938 0.4064)
			(end -1.1938 -0.4064)
			(stroke
				(width 0.1)
				(type default)
			)
			(layer "F.Fab")
		)
		(fp_line
			(start -1.1938 -0.4064)
			(end -0.8636 -0.4064)
			(stroke
				(width 0.1)
				(type default)
			)
			(layer "F.Fab")
		)
		(pad "1" smd rect
			(at -0.7366 0 90)
			(size 0.7112 0.8128)
			(layers "F.Cu" "F.Mask" "F.Paste")
			(net "P12V_HSC_TEMP_D+")
		)
		(pad "2" smd rect
			(at 0.7366 0 90)
			(size 0.7112 0.8128)
			(layers "F.Cu" "F.Mask" "F.Paste")
			(net "P12V_HSC_TEMP_D-")
		)
	)
	(footprint ""
		(layer "F.Cu")
		(at 148.944076 -23.284942 -90)
		(property "Reference" "R364"
			(at 0 0 270)
			(layer "F.SilkS")
			(hide yes)
			(effects
				(font
					(size 1.27 1.27)
				)
			)
		)
		(property "Value" ""
			(at 0 0 270)
			(layer "F.Fab")
			(effects
				(font
					(size 1.27 1.27)
				)
			)
		)
		(duplicate_pad_numbers_are_jumpers no)
		(fp_line
			(start -0.7874 0.4064)
			(end -0.7874 -0.4064)
			(stroke
				(width 0.1524)
				(type default)
			)
			(layer "F.SilkS")
		)
		(fp_line
			(start 0.7874 0.4064)
			(end -0.7874 0.4064)
			(stroke
				(width 0.1524)
				(type default)
			)
			(layer "F.SilkS")
		)
		(fp_line
			(start -0.7874 -0.4064)
			(end 0.7874 -0.4064)
			(stroke
				(width 0.1524)
				(type default)
			)
			(layer "F.SilkS")
		)
		(fp_line
			(start 0.7874 -0.4064)
			(end 0.7874 0.4064)
			(stroke
				(width 0.1524)
				(type default)
			)
			(layer "F.SilkS")
		)
		(fp_line
			(start -0.67945 0.3048)
			(end -0.67945 -0.305054)
			(stroke
				(width 0.1)
				(type default)
			)
			(layer "F.Fab")
		)
		(fp_line
			(start -0.12065 0.3048)
			(end -0.67945 0.3048)
			(stroke
				(width 0.1)
				(type default)
			)
			(layer "F.Fab")
		)
		(fp_line
			(start 0.120396 0.3048)
			(end 0.120396 0.2794)
			(stroke
				(width 0.1)
				(type default)
			)
			(layer "F.Fab")
		)
		(fp_line
			(start 0.67945 0.3048)
			(end 0.120396 0.3048)
			(stroke
				(width 0.1)
				(type default)
			)
			(layer "F.Fab")
		)
		(fp_line
			(start -0.12065 0.2794)
			(end -0.12065 0.3048)
			(stroke
				(width 0.1)
				(type default)
			)
			(layer "F.Fab")
		)
		(fp_line
			(start 0.120396 0.2794)
			(end -0.12065 0.2794)
			(stroke
				(width 0.1)
				(type default)
			)
			(layer "F.Fab")
		)
		(fp_line
			(start -0.12065 -0.2794)
			(end 0.12065 -0.2794)
			(stroke
				(width 0.1)
				(type default)
			)
			(layer "F.Fab")
		)
		(fp_line
			(start 0.12065 -0.2794)
			(end 0.12065 -0.3048)
			(stroke
				(width 0.1)
				(type default)
			)
			(layer "F.Fab")
		)
		(fp_line
			(start 0.12065 -0.3048)
			(end 0.67945 -0.3048)
			(stroke
				(width 0.1)
				(type default)
			)
			(layer "F.Fab")
		)
		(fp_line
			(start 0.67945 -0.3048)
			(end 0.67945 0.3048)
			(stroke
				(width 0.1)
				(type default)
			)
			(layer "F.Fab")
		)
		(fp_line
			(start -0.67945 -0.305054)
			(end -0.12065 -0.305054)
			(stroke
				(width 0.1)
				(type default)
			)
			(layer "F.Fab")
		)
		(fp_line
			(start -0.12065 -0.305054)
			(end -0.12065 -0.2794)
			(stroke
				(width 0.1)
				(type default)
			)
			(layer "F.Fab")
		)
		(pad "1" smd circle
			(at -0.40005 0 270)
			(size 0 0)
			(layers "F.Cu" "F.Mask" "F.Paste")
			(net "P3V_BAT_R")
		)
		(pad "2" smd circle
			(at 0.40005 0 270)
			(size 0 0)
			(layers "F.Cu" "F.Mask" "F.Paste")
			(net "SCM_VDD_RTC")
		)
	)
	(footprint ""
		(layer "F.Cu")
		(at 403.977348 -17.624298 90)
		(property "Reference" "C1558"
			(at 0 0 90)
			(layer "F.SilkS")
			(hide yes)
			(effects
				(font
					(size 1.27 1.27)
				)
			)
		)
		(property "Value" ""
			(at 0 0 90)
			(layer "F.Fab")
			(effects
				(font
					(size 1.27 1.27)
				)
			)
		)
		(duplicate_pad_numbers_are_jumpers no)
		(fp_line
			(start 0.299974 -0.150114)
			(end 0.299974 0.150114)
			(stroke
				(width 0.1)
				(type default)
			)
			(layer "F.Fab")
		)
		(fp_line
			(start -0.299974 -0.150114)
			(end 0.299974 -0.150114)
			(stroke
				(width 0.1)
				(type default)
			)
			(layer "F.Fab")
		)
		(fp_line
			(start 0.299974 0.150114)
			(end -0.299974 0.150114)
			(stroke
				(width 0.1)
				(type default)
			)
			(layer "F.Fab")
		)
		(fp_line
			(start -0.299974 0.150114)
			(end -0.299974 -0.150114)
			(stroke
				(width 0.1)
				(type default)
			)
			(layer "F.Fab")
		)
		(pad "1" smd rect
			(at -0.2667 0 90)
			(size 0.3048 0.381)
			(layers "F.Cu" "F.Mask" "F.Paste")
			(net "P5E_CPU0_G3_TX_C_DN<10>")
		)
		(pad "2" smd rect
			(at 0.2667 0 90)
			(size 0.3048 0.381)
			(layers "F.Cu" "F.Mask" "F.Paste")
			(net "P5E_CPU0_G3_TX_DN<10>")
		)
	)
	(footprint ""
		(layer "F.Cu")
		(at 281.905456 -434.655976 180)
		(property "Reference" "R4268"
			(at 0 0 180)
			(layer "F.SilkS")
			(hide yes)
			(effects
				(font
					(size 1.27 1.27)
				)
			)
		)
		(property "Value" ""
			(at 0 0 180)
			(layer "F.Fab")
			(effects
				(font
					(size 1.27 1.27)
				)
			)
		)
		(duplicate_pad_numbers_are_jumpers no)
		(fp_line
			(start 0.7874 0.4064)
			(end -0.7874 0.4064)
			(stroke
				(width 0.1524)
				(type default)
			)
			(layer "F.SilkS")
		)
		(fp_line
			(start 0.7874 -0.4064)
			(end 0.7874 0.4064)
			(stroke
				(width 0.1524)
				(type default)
			)
			(layer "F.SilkS")
		)
		(fp_line
			(start -0.7874 0.4064)
			(end -0.7874 -0.4064)
			(stroke
				(width 0.1524)
				(type default)
			)
			(layer "F.SilkS")
		)
		(fp_line
			(start -0.7874 -0.4064)
			(end 0.7874 -0.4064)
			(stroke
				(width 0.1524)
				(type default)
			)
			(layer "F.SilkS")
		)
		(fp_line
			(start 0.67945 0.3048)
			(end 0.120396 0.3048)
			(stroke
				(width 0.1)
				(type default)
			)
			(layer "F.Fab")
		)
		(fp_line
			(start 0.67945 -0.3048)
			(end 0.67945 0.3048)
			(stroke
				(width 0.1)
				(type default)
			)
			(layer "F.Fab")
		)
		(fp_line
			(start 0.12065 -0.2794)
			(end 0.12065 -0.3048)
			(stroke
				(width 0.1)
				(type default)
			)
			(layer "F.Fab")
		)
		(fp_line
			(start 0.12065 -0.3048)
			(end 0.67945 -0.3048)
			(stroke
				(width 0.1)
				(type default)
			)
			(layer "F.Fab")
		)
		(fp_line
			(start 0.120396 0.3048)
			(end 0.120396 0.2794)
			(stroke
				(width 0.1)
				(type default)
			)
			(layer "F.Fab")
		)
		(fp_line
			(start 0.120396 0.2794)
			(end -0.12065 0.2794)
			(stroke
				(width 0.1)
				(type default)
			)
			(layer "F.Fab")
		)
		(fp_line
			(start -0.12065 0.3048)
			(end -0.67945 0.3048)
			(stroke
				(width 0.1)
				(type default)
			)
			(layer "F.Fab")
		)
		(fp_line
			(start -0.12065 0.2794)
			(end -0.12065 0.3048)
			(stroke
				(width 0.1)
				(type default)
			)
			(layer "F.Fab")
		)
		(fp_line
			(start -0.12065 -0.2794)
			(end 0.12065 -0.2794)
			(stroke
				(width 0.1)
				(type default)
			)
			(layer "F.Fab")
		)
		(fp_line
			(start -0.12065 -0.305054)
			(end -0.12065 -0.2794)
			(stroke
				(width 0.1)
				(type default)
			)
			(layer "F.Fab")
		)
		(fp_line
			(start -0.67945 0.3048)
			(end -0.67945 -0.305054)
			(stroke
				(width 0.1)
				(type default)
			)
			(layer "F.Fab")
		)
		(fp_line
			(start -0.67945 -0.305054)
			(end -0.12065 -0.305054)
			(stroke
				(width 0.1)
				(type default)
			)
			(layer "F.Fab")
		)
		(pad "1" smd circle
			(at -0.40005 0 180)
			(size 0 0)
			(layers "F.Cu" "F.Mask" "F.Paste")
			(net "PWRGD_P3V3_AUX_PDB")
		)
		(pad "2" smd circle
			(at 0.40005 0 180)
			(size 0 0)
			(layers "F.Cu" "F.Mask" "F.Paste")
			(net "PWRGD_P3V3_AUX_PDB_R")
		)
	)
	(footprint ""
		(layer "F.Cu")
		(at 180.528468 -53.980334)
		(property "Reference" "C1099"
			(at 0 0 0)
			(layer "F.SilkS")
			(hide yes)
			(effects
				(font
					(size 1.27 1.27)
				)
			)
		)
		(property "Value" ""
			(at 0 0 0)
			(layer "F.Fab")
			(effects
				(font
					(size 1.27 1.27)
				)
			)
		)
		(duplicate_pad_numbers_are_jumpers no)
		(fp_line
			(start -0.299974 -0.150114)
			(end 0.299974 -0.150114)
			(stroke
				(width 0.1)
				(type default)
			)
			(layer "F.Fab")
		)
		(fp_line
			(start -0.299974 0.150114)
			(end -0.299974 -0.150114)
			(stroke
				(width 0.1)
				(type default)
			)
			(layer "F.Fab")
		)
		(fp_line
			(start 0.299974 -0.150114)
			(end 0.299974 0.150114)
			(stroke
				(width 0.1)
				(type default)
			)
			(layer "F.Fab")
		)
		(fp_line
			(start 0.299974 0.150114)
			(end -0.299974 0.150114)
			(stroke
				(width 0.1)
				(type default)
			)
			(layer "F.Fab")
		)
		(pad "1" smd rect
			(at -0.2667 0)
			(size 0.3048 0.381)
			(layers "F.Cu" "F.Mask" "F.Paste")
			(net "P3E_CPU1_P4_TX_C_DN<3>")
		)
		(pad "2" smd rect
			(at 0.2667 0)
			(size 0.3048 0.381)
			(layers "F.Cu" "F.Mask" "F.Paste")
			(net "P3E_CPU1_P4_TX_DN<3>")
		)
	)
	(footprint ""
		(layer "F.Cu")
		(at 109.136942 -19.9898 -90)
		(property "Reference" "R6272"
			(at 0 0 270)
			(layer "F.SilkS")
			(hide yes)
			(effects
				(font
					(size 1.27 1.27)
				)
			)
		)
		(property "Value" ""
			(at 0 0 270)
			(layer "F.Fab")
			(effects
				(font
					(size 1.27 1.27)
				)
			)
		)
		(duplicate_pad_numbers_are_jumpers no)
		(fp_line
			(start -0.7874 0.4064)
			(end -0.7874 -0.4064)
			(stroke
				(width 0.1524)
				(type default)
			)
			(layer "F.SilkS")
		)
		(fp_line
			(start 0.7874 0.4064)
			(end -0.7874 0.4064)
			(stroke
				(width 0.1524)
				(type default)
			)
			(layer "F.SilkS")
		)
		(fp_line
			(start -0.7874 -0.4064)
			(end 0.7874 -0.4064)
			(stroke
				(width 0.1524)
				(type default)
			)
			(layer "F.SilkS")
		)
		(fp_line
			(start 0.7874 -0.4064)
			(end 0.7874 0.4064)
			(stroke
				(width 0.1524)
				(type default)
			)
			(layer "F.SilkS")
		)
		(fp_line
			(start -0.67945 0.3048)
			(end -0.67945 -0.305054)
			(stroke
				(width 0.1)
				(type default)
			)
			(layer "F.Fab")
		)
		(fp_line
			(start -0.12065 0.3048)
			(end -0.67945 0.3048)
			(stroke
				(width 0.1)
				(type default)
			)
			(layer "F.Fab")
		)
		(fp_line
			(start 0.120396 0.3048)
			(end 0.120396 0.2794)
			(stroke
				(width 0.1)
				(type default)
			)
			(layer "F.Fab")
		)
		(fp_line
			(start 0.67945 0.3048)
			(end 0.120396 0.3048)
			(stroke
				(width 0.1)
				(type default)
			)
			(layer "F.Fab")
		)
		(fp_line
			(start -0.12065 0.2794)
			(end -0.12065 0.3048)
			(stroke
				(width 0.1)
				(type default)
			)
			(layer "F.Fab")
		)
		(fp_line
			(start 0.120396 0.2794)
			(end -0.12065 0.2794)
			(stroke
				(width 0.1)
				(type default)
			)
			(layer "F.Fab")
		)
		(fp_line
			(start -0.12065 -0.2794)
			(end 0.12065 -0.2794)
			(stroke
				(width 0.1)
				(type default)
			)
			(layer "F.Fab")
		)
		(fp_line
			(start 0.12065 -0.2794)
			(end 0.12065 -0.3048)
			(stroke
				(width 0.1)
				(type default)
			)
			(layer "F.Fab")
		)
		(fp_line
			(start 0.12065 -0.3048)
			(end 0.67945 -0.3048)
			(stroke
				(width 0.1)
				(type default)
			)
			(layer "F.Fab")
		)
		(fp_line
			(start 0.67945 -0.3048)
			(end 0.67945 0.3048)
			(stroke
				(width 0.1)
				(type default)
			)
			(layer "F.Fab")
		)
		(fp_line
			(start -0.67945 -0.305054)
			(end -0.12065 -0.305054)
			(stroke
				(width 0.1)
				(type default)
			)
			(layer "F.Fab")
		)
		(fp_line
			(start -0.12065 -0.305054)
			(end -0.12065 -0.2794)
			(stroke
				(width 0.1)
				(type default)
			)
			(layer "F.Fab")
		)
		(pad "1" smd circle
			(at -0.40005 0 270)
			(size 0 0)
			(layers "F.Cu" "F.Mask" "F.Paste")
			(net "USB_HUB2_MRP_CFG_STRAP")
		)
		(pad "2" smd circle
			(at 0.40005 0 270)
			(size 0 0)
			(layers "F.Cu" "F.Mask" "F.Paste")
			(net "GND")
		)
	)
)
